# T6G (Grand Teton) — schematic netlist excerpt (pin names and nets, part order shuffled) for the footprints in the layout excerpt that follows; sources: Cadence DE-HDL packaged netlist, KiCad conversion of 04192023_DAF0TMB3IC0_F0TG_MB_C_brd_V02_OCP.brd

C1105  Q_CAP  0.1UF 25V 10% X7R  pkg 0402  page 77 : A = P3V3_AUX ; B = GND
PC638  Q_CAP  0.1UF 25V 10% X7R  pkg 0402  page 224 : A = PVDD11_S3_P1_VMON ; B = GND
C6510  Q_CAP_DIFFBUS  DIFF BUS_0.22UF 6.3V 20% X6S  pkg C0201  page 275 : \1\ = P5E_CPU0_P0_TX_BUF_C_DN<4> ; \2\ = P5E_CPU0_P0_TX_BUF_DN<4>

(kicad_pcb
	(version 20260206)
	(generator "pcbnew")
	(generator_version "10.0")
	(general
		(thickness 1.6)
		(legacy_teardrops no)
	)
	(paper "A4")
	(title_block
		(title "04192023_DAF0TMB3IC0_F0TG_MB_C_brd_V02_OCP.brd")
		(comment 1 "Grand Teton / footprints 1484-1486 of 8354")
	)
	(layers
		(0 "F.Cu" signal "TOP")
		(4 "In1.Cu" signal "GND")
		(6 "In2.Cu" signal "IN1")
		(8 "In3.Cu" signal "GND1")
		(10 "In4.Cu" signal "IN2")
		(12 "In5.Cu" signal "GND2")
		(14 "In6.Cu" signal "IN3")
		(16 "In7.Cu" signal "GND3")
		(18 "In8.Cu" signal "VCC")
		(20 "In9.Cu" signal "VCC1")
		(22 "In10.Cu" signal "GND4")
		(24 "In11.Cu" signal "IN4")
		(26 "In12.Cu" signal "GND5")
		(28 "In13.Cu" signal "IN5")
		(30 "In14.Cu" signal "GND6")
		(32 "In15.Cu" signal "IN6")
		(34 "In16.Cu" signal "GND7")
		(2 "B.Cu" signal "BOTTOM")
		(9 "F.Adhes" user "F.Adhesive")
		(11 "B.Adhes" user "B.Adhesive")
		(13 "F.Paste" user "Package Geometry/Pastemask Top")
		(15 "B.Paste" user "Package Geometry/Pastemask Bottom")
		(5 "F.SilkS" user "Ref Des/Silkscreen Top")
		(7 "B.SilkS" user "Ref Des/Silkscreen Bottom")
		(1 "F.Mask" user "Board Geometry/Soldermask Top")
		(3 "B.Mask" user "Board Geometry/Soldermask Bottom")
		(17 "Dwgs.User" user "User.Drawings")
		(19 "Cmts.User" user "User.Comments")
		(21 "Eco1.User" user "User.Eco1")
		(23 "Eco2.User" user "User.Eco2")
		(25 "Edge.Cuts" user "Board Geometry/Outline")
		(27 "Margin" user)
		(31 "F.CrtYd" user "Package Geometry/Place Bound Top")
		(29 "B.CrtYd" user "Package Geometry/Place Bound Bottom")
		(35 "F.Fab" user "Ref Des/Assembly Top")
		(33 "B.Fab" user "Ref Des/Assembly Bottom")
	)
	(footprint ""
		(layer "F.Cu")
		(at 259.131308 -137.103104 -90)
		(property "Reference" "C1105"
			(at 0 0 270)
			(layer "F.SilkS")
			(hide yes)
			(effects
				(font
					(size 1.27 1.27)
				)
			)
		)
		(property "Value" ""
			(at 0 0 270)
			(layer "F.Fab")
			(effects
				(font
					(size 1.27 1.27)
				)
			)
		)
		(duplicate_pad_numbers_are_jumpers no)
		(fp_line
			(start -0.7874 0.4064)
			(end -0.7874 -0.4064)
			(stroke
				(width 0.1524)
				(type default)
			)
			(layer "F.SilkS")
		)
		(fp_line
			(start 0.7874 0.4064)
			(end -0.7874 0.4064)
			(stroke
				(width 0.1524)
				(type default)
			)
			(layer "F.SilkS")
		)
		(fp_line
			(start -0.7874 -0.4064)
			(end 0.7874 -0.4064)
			(stroke
				(width 0.1524)
				(type default)
			)
			(layer "F.SilkS")
		)
		(fp_line
			(start 0.7874 -0.4064)
			(end 0.7874 0.4064)
			(stroke
				(width 0.1524)
				(type default)
			)
			(layer "F.SilkS")
		)
		(fp_line
			(start -0.67945 0.3048)
			(end -0.67945 -0.305054)
			(stroke
				(width 0.1)
				(type default)
			)
			(layer "F.Fab")
		)
		(fp_line
			(start -0.12065 0.3048)
			(end -0.67945 0.3048)
			(stroke
				(width 0.1)
				(type default)
			)
			(layer "F.Fab")
		)
		(fp_line
			(start 0.120396 0.3048)
			(end 0.120396 0.2794)
			(stroke
				(width 0.1)
				(type default)
			)
			(layer "F.Fab")
		)
		(fp_line
			(start 0.67945 0.3048)
			(end 0.120396 0.3048)
			(stroke
				(width 0.1)
				(type default)
			)
			(layer "F.Fab")
		)
		(fp_line
			(start -0.12065 0.2794)
			(end -0.12065 0.3048)
			(stroke
				(width 0.1)
				(type default)
			)
			(layer "F.Fab")
		)
		(fp_line
			(start 0.120396 0.2794)
			(end -0.12065 0.2794)
			(stroke
				(width 0.1)
				(type default)
			)
			(layer "F.Fab")
		)
		(fp_line
			(start -0.12065 -0.2794)
			(end 0.12065 -0.2794)
			(stroke
				(width 0.1)
				(type default)
			)
			(layer "F.Fab")
		)
		(fp_line
			(start 0.12065 -0.2794)
			(end 0.12065 -0.3048)
			(stroke
				(width 0.1)
				(type default)
			)
			(layer "F.Fab")
		)
		(fp_line
			(start 0.12065 -0.3048)
			(end 0.67945 -0.3048)
			(stroke
				(width 0.1)
				(type default)
			)
			(layer "F.Fab")
		)
		(fp_line
			(start 0.67945 -0.3048)
			(end 0.67945 0.3048)
			(stroke
				(width 0.1)
				(type default)
			)
			(layer "F.Fab")
		)
		(fp_line
			(start -0.67945 -0.305054)
			(end -0.12065 -0.305054)
			(stroke
				(width 0.1)
				(type default)
			)
			(layer "F.Fab")
		)
		(fp_line
			(start -0.12065 -0.305054)
			(end -0.12065 -0.2794)
			(stroke
				(width 0.1)
				(type default)
			)
			(layer "F.Fab")
		)
		(pad "1" smd circle
			(at -0.40005 0 270)
			(size 0 0)
			(layers "F.Cu" "F.Mask" "F.Paste")
			(net "P3V3_AUX")
		)
		(pad "2" smd circle
			(at 0.40005 0 270)
			(size 0 0)
			(layers "F.Cu" "F.Mask" "F.Paste")
			(net "GND")
		)
	)
	(footprint ""
		(layer "F.Cu")
		(at 166.929308 -349.265494)
		(property "Reference" "PC638"
			(at 0 0 0)
			(layer "F.SilkS")
			(hide yes)
			(effects
				(font
					(size 1.27 1.27)
				)
			)
		)
		(property "Value" ""
			(at 0 0 0)
			(layer "F.Fab")
			(effects
				(font
					(size 1.27 1.27)
				)
			)
		)
		(duplicate_pad_numbers_are_jumpers no)
		(fp_line
			(start -0.7874 -0.4064)
			(end 0.7874 -0.4064)
			(stroke
				(width 0.1524)
				(type default)
			)
			(layer "F.SilkS")
		)
		(fp_line
			(start -0.7874 0.4064)
			(end -0.7874 -0.4064)
			(stroke
				(width 0.1524)
				(type default)
			)
			(layer "F.SilkS")
		)
		(fp_line
			(start 0.7874 -0.4064)
			(end 0.7874 0.4064)
			(stroke
				(width 0.1524)
				(type default)
			)
			(layer "F.SilkS")
		)
		(fp_line
			(start 0.7874 0.4064)
			(end -0.7874 0.4064)
			(stroke
				(width 0.1524)
				(type default)
			)
			(layer "F.SilkS")
		)
		(fp_line
			(start -0.67945 -0.305054)
			(end -0.12065 -0.305054)
			(stroke
				(width 0.1)
				(type default)
			)
			(layer "F.Fab")
		)
		(fp_line
			(start -0.67945 0.3048)
			(end -0.67945 -0.305054)
			(stroke
				(width 0.1)
				(type default)
			)
			(layer "F.Fab")
		)
		(fp_line
			(start -0.12065 -0.305054)
			(end -0.12065 -0.2794)
			(stroke
				(width 0.1)
				(type default)
			)
			(layer "F.Fab")
		)
		(fp_line
			(start -0.12065 -0.2794)
			(end 0.12065 -0.2794)
			(stroke
				(width 0.1)
				(type default)
			)
			(layer "F.Fab")
		)
		(fp_line
			(start -0.12065 0.2794)
			(end -0.12065 0.3048)
			(stroke
				(width 0.1)
				(type default)
			)
			(layer "F.Fab")
		)
		(fp_line
			(start -0.12065 0.3048)
			(end -0.67945 0.3048)
			(stroke
				(width 0.1)
				(type default)
			)
			(layer "F.Fab")
		)
		(fp_line
			(start 0.120396 0.2794)
			(end -0.12065 0.2794)
			(stroke
				(width 0.1)
				(type default)
			)
			(layer "F.Fab")
		)
		(fp_line
			(start 0.120396 0.3048)
			(end 0.120396 0.2794)
			(stroke
				(width 0.1)
				(type default)
			)
			(layer "F.Fab")
		)
		(fp_line
			(start 0.12065 -0.3048)
			(end 0.67945 -0.3048)
			(stroke
				(width 0.1)
				(type default)
			)
			(layer "F.Fab")
		)
		(fp_line
			(start 0.12065 -0.2794)
			(end 0.12065 -0.3048)
			(stroke
				(width 0.1)
				(type default)
			)
			(layer "F.Fab")
		)
		(fp_line
			(start 0.67945 -0.3048)
			(end 0.67945 0.3048)
			(stroke
				(width 0.1)
				(type default)
			)
			(layer "F.Fab")
		)
		(fp_line
			(start 0.67945 0.3048)
			(end 0.120396 0.3048)
			(stroke
				(width 0.1)
				(type default)
			)
			(layer "F.Fab")
		)
		(pad "1" smd circle
			(at -0.40005 0)
			(size 0 0)
			(layers "F.Cu" "F.Mask" "F.Paste")
			(net "PVDD11_S3_P1_VMON")
		)
		(pad "2" smd circle
			(at 0.40005 0)
			(size 0 0)
			(layers "F.Cu" "F.Mask" "F.Paste")
			(net "GND")
		)
	)
	(footprint ""
		(layer "F.Cu")
		(at 316.021466 -416.899344 -90)
		(property "Reference" "C6510"
			(at 0 0 270)
			(layer "F.SilkS")
			(hide yes)
			(effects
				(font
					(size 1.27 1.27)
				)
			)
		)
		(property "Value" ""
			(at 0 0 270)
			(layer "F.Fab")
			(effects
				(font
					(size 1.27 1.27)
				)
			)
		)
		(duplicate_pad_numbers_are_jumpers no)
		(fp_line
			(start -0.299974 0.150114)
			(end -0.299974 -0.150114)
			(stroke
				(width 0.1)
				(type default)
			)
			(layer "F.Fab")
		)
		(fp_line
			(start 0.299974 0.150114)
			(end -0.299974 0.150114)
			(stroke
				(width 0.1)
				(type default)
			)
			(layer "F.Fab")
		)
		(fp_line
			(start -0.299974 -0.150114)
			(end 0.299974 -0.150114)
			(stroke
				(width 0.1)
				(type default)
			)
			(layer "F.Fab")
		)
		(fp_line
			(start 0.299974 -0.150114)
			(end 0.299974 0.150114)
			(stroke
				(width 0.1)
				(type default)
			)
			(layer "F.Fab")
		)
		(pad "1" smd rect
			(at -0.2667 0 270)
			(size 0.3048 0.381)
			(layers "F.Cu" "F.Mask" "F.Paste")
			(net "P5E_CPU0_P0_TX_BUF_C_DN<4>")
		)
		(pad "2" smd rect
			(at 0.2667 0 270)
			(size 0.3048 0.381)
			(layers "F.Cu" "F.Mask" "F.Paste")
			(net "P5E_CPU0_P0_TX_BUF_DN<4>")
		)
	)
)
